FILE_TYPE=LIBRARY_PARTS;
TIME=' COMPILATION ON WED MAY 18 15:51:34 1994  ';
primitive 'sconn60_c21100002';
  pin
    'IO1':
      PIN_NUMBER='(1)';
      PIN_TYPE='UNSPEC';
    'IO3':
      PIN_NUMBER='(3)';
      PIN_TYPE='UNSPEC';
    'IO5':
      PIN_NUMBER='(5)';
      PIN_TYPE='UNSPEC';
    'IO7':
      PIN_NUMBER='(7)';
      PIN_TYPE='UNSPEC';
    'IO9':
      PIN_NUMBER='(9)';
      PIN_TYPE='UNSPEC';
    'IO11':
      PIN_NUMBER='(11)';
      PIN_TYPE='UNSPEC';
    'IO13':
      PIN_NUMBER='(13)';
      PIN_TYPE='UNSPEC';
    'IO15':
      PIN_NUMBER='(15)';
      PIN_TYPE='UNSPEC';
    'IO17':
      PIN_NUMBER='(17)';
      PIN_TYPE='UNSPEC';
    'IO19':
      PIN_NUMBER='(19)';
      PIN_TYPE='UNSPEC';
    'IO21':
      PIN_NUMBER='(21)';
      PIN_TYPE='UNSPEC';
    'IO23':
      PIN_NUMBER='(23)';
      PIN_TYPE='UNSPEC';
    'IO25':
      PIN_NUMBER='(25)';
      PIN_TYPE='UNSPEC';
    'IO27':
      PIN_NUMBER='(27)';
      PIN_TYPE='UNSPEC';
    'IO29':
      PIN_NUMBER='(29)';
      PIN_TYPE='UNSPEC';
    'IO31':
      PIN_NUMBER='(31)';
      PIN_TYPE='UNSPEC';
    'IO33':
      PIN_NUMBER='(33)';
      PIN_TYPE='UNSPEC';
    'IO35':
      PIN_NUMBER='(35)';
      PIN_TYPE='UNSPEC';
    'IO37':
      PIN_NUMBER='(37)';
      PIN_TYPE='UNSPEC';
    'IO39':
      PIN_NUMBER='(39)';
      PIN_TYPE='UNSPEC';
    'IO41':
      PIN_NUMBER='(41)';
      PIN_TYPE='UNSPEC';
    'IO43':
      PIN_NUMBER='(43)';
      PIN_TYPE='UNSPEC';
    'IO45':
      PIN_NUMBER='(45)';
      PIN_TYPE='UNSPEC';
    'IO47':
      PIN_NUMBER='(47)';
      PIN_TYPE='UNSPEC';
    'IO49':
      PIN_NUMBER='(49)';
      PIN_TYPE='UNSPEC';
    'IO2':
      PIN_NUMBER='(2)';
      PIN_TYPE='UNSPEC';
    'IO4':
      PIN_NUMBER='(4)';
      PIN_TYPE='UNSPEC';
    'IO6':
      PIN_NUMBER='(6)';
      PIN_TYPE='UNSPEC';
    'IO8':
      PIN_NUMBER='(8)';
      PIN_TYPE='UNSPEC';
    'IO10':
      PIN_NUMBER='(10)';
      PIN_TYPE='UNSPEC';
    'IO12':
      PIN_NUMBER='(12)';
      PIN_TYPE='UNSPEC';
    'IO14':
      PIN_NUMBER='(14)';
      PIN_TYPE='UNSPEC';
    'IO16':
      PIN_NUMBER='(16)';
      PIN_TYPE='UNSPEC';
    'IO18':
      PIN_NUMBER='(18)';
      PIN_TYPE='UNSPEC';
    'IO20':
      PIN_NUMBER='(20)';
      PIN_TYPE='UNSPEC';
    'IO22':
      PIN_NUMBER='(22)';
      PIN_TYPE='UNSPEC';
    'IO24':
      PIN_NUMBER='(24)';
      PIN_TYPE='UNSPEC';
    'IO26':
      PIN_NUMBER='(26)';
      PIN_TYPE='UNSPEC';
    'IO28':
      PIN_NUMBER='(28)';
      PIN_TYPE='UNSPEC';
    'IO30':
      PIN_NUMBER='(30)';
      PIN_TYPE='UNSPEC';
    'IO32':
      PIN_NUMBER='(32)';
      PIN_TYPE='UNSPEC';
    'IO34':
      PIN_NUMBER='(34)';
      PIN_TYPE='UNSPEC';
    'IO36':
      PIN_NUMBER='(36)';
      PIN_TYPE='UNSPEC';
    'IO38':
      PIN_NUMBER='(38)';
      PIN_TYPE='UNSPEC';
    'IO40':
      PIN_NUMBER='(40)';
      PIN_TYPE='UNSPEC';
    'IO42':
      PIN_NUMBER='(42)';
      PIN_TYPE='UNSPEC';
    'IO44':
      PIN_NUMBER='(44)';
      PIN_TYPE='UNSPEC';
    'IO46':
      PIN_NUMBER='(46)';
      PIN_TYPE='UNSPEC';
    'IO48':
      PIN_NUMBER='(48)';
      PIN_TYPE='UNSPEC';
    'IO50':
      PIN_NUMBER='(50)';
      PIN_TYPE='UNSPEC';
    'IO51':
      PIN_NUMBER='(51)';
      PIN_TYPE='UNSPEC';
    'IO52':
      PIN_NUMBER='(52)';
      PIN_TYPE='UNSPEC';
    'IO53':
      PIN_NUMBER='(53)';
      PIN_TYPE='UNSPEC';
    'IO54':
      PIN_NUMBER='(54)';
      PIN_TYPE='UNSPEC';
    'IO55':
      PIN_NUMBER='(55)';
      PIN_TYPE='UNSPEC';
    'IO56':
      PIN_NUMBER='(56)';
      PIN_TYPE='UNSPEC';
    'IO57':
      PIN_NUMBER='(57)';
      PIN_TYPE='UNSPEC';
    'IO58':
      PIN_NUMBER='(58)';
      PIN_TYPE='UNSPEC';
    'IO59':
      PIN_NUMBER='(59)';
      PIN_TYPE='UNSPEC';
    'IO60':
      PIN_NUMBER='(60)';
      PIN_TYPE='UNSPEC';
  end_pin;
  body
    BODY_NAME='sconn60_c21100002';
    PART_NAME='sconn60_c21100002';
    PHYS_DES_PREFIX='J';
  end_body;
end_primitive;
END.
